# T6G (Grand Teton) — schematic netlist excerpt (pin names and nets, part order shuffled) for the footprints in the layout excerpt that follows; sources: Cadence DE-HDL packaged netlist, KiCad conversion of 04192023_DAF0TMB3IC0_F0TG_MB_C_brd_V02_OCP.brd

X11  TP_TDR_4P_FTS  TP_TDR_4P_DIP EMPTY  pkg TH  page 260
  S1  = TDR_DIFF_80_IN4_DN
  P1  = T1_GND
  P2  = T1_GND
  S2  = TDR_DIFF_80_IN4_DP

R251  Q_RES  0 5% CHIP  pkg 0402LF  page 81 : A = CPU0_SPD_HOST_CTRL_R1_N ; B = CPU0_SPD_HOST_CTRL_N

(kicad_pcb
	(version 20260206)
	(generator "pcbnew")
	(generator_version "10.0")
	(general
		(thickness 1.6)
		(legacy_teardrops no)
	)
	(paper "A4")
	(title_block
		(title "04192023_DAF0TMB3IC0_F0TG_MB_C_brd_V02_OCP.brd")
		(comment 1 "Grand Teton / footprints 7345-7346 of 8354")
	)
	(layers
		(0 "F.Cu" signal "TOP")
		(4 "In1.Cu" signal "GND")
		(6 "In2.Cu" signal "IN1")
		(8 "In3.Cu" signal "GND1")
		(10 "In4.Cu" signal "IN2")
		(12 "In5.Cu" signal "GND2")
		(14 "In6.Cu" signal "IN3")
		(16 "In7.Cu" signal "GND3")
		(18 "In8.Cu" signal "VCC")
		(20 "In9.Cu" signal "VCC1")
		(22 "In10.Cu" signal "GND4")
		(24 "In11.Cu" signal "IN4")
		(26 "In12.Cu" signal "GND5")
		(28 "In13.Cu" signal "IN5")
		(30 "In14.Cu" signal "GND6")
		(32 "In15.Cu" signal "IN6")
		(34 "In16.Cu" signal "GND7")
		(2 "B.Cu" signal "BOTTOM")
		(9 "F.Adhes" user "F.Adhesive")
		(11 "B.Adhes" user "B.Adhesive")
		(13 "F.Paste" user "Package Geometry/Pastemask Top")
		(15 "B.Paste" user "Package Geometry/Pastemask Bottom")
		(5 "F.SilkS" user "Ref Des/Silkscreen Top")
		(7 "B.SilkS" user "Ref Des/Silkscreen Bottom")
		(1 "F.Mask" user "Board Geometry/Soldermask Top")
		(3 "B.Mask" user "Board Geometry/Soldermask Bottom")
		(17 "Dwgs.User" user "User.Drawings")
		(19 "Cmts.User" user "User.Comments")
		(21 "Eco1.User" user "User.Eco1")
		(23 "Eco2.User" user "User.Eco2")
		(25 "Edge.Cuts" user "Board Geometry/Outline")
		(27 "Margin" user)
		(31 "F.CrtYd" user "Package Geometry/Place Bound Top")
		(29 "B.CrtYd" user "Package Geometry/Place Bound Bottom")
		(35 "F.Fab" user "Ref Des/Assembly Top")
		(33 "B.Fab" user "Ref Des/Assembly Bottom")
	)
	(footprint ""
		(layer "B.Cu")
		(at 191.000888 -126.861824 -90)
		(property "Reference" "R251"
			(at 0 0 90)
			(layer "B.SilkS")
			(hide yes)
			(effects
				(font
					(size 1.27 1.27)
				)
				(justify mirror)
			)
		)
		(property "Value" ""
			(at 0 0 90)
			(layer "B.Fab")
			(effects
				(font
					(size 1.27 1.27)
				)
				(justify mirror)
			)
		)
		(duplicate_pad_numbers_are_jumpers no)
		(fp_line
			(start -0.7874 0.4064)
			(end 0.7874 0.4064)
			(stroke
				(width 0.1524)
				(type default)
			)
			(layer "B.SilkS")
		)
		(fp_line
			(start 0.7874 0.4064)
			(end 0.7874 -0.4064)
			(stroke
				(width 0.1524)
				(type default)
			)
			(layer "B.SilkS")
		)
		(fp_line
			(start -0.7874 -0.4064)
			(end -0.7874 0.4064)
			(stroke
				(width 0.1524)
				(type default)
			)
			(layer "B.SilkS")
		)
		(fp_line
			(start 0.7874 -0.4064)
			(end -0.7874 -0.4064)
			(stroke
				(width 0.1524)
				(type default)
			)
			(layer "B.SilkS")
		)
		(fp_line
			(start -0.67945 0.3048)
			(end -0.120396 0.3048)
			(stroke
				(width 0.1)
				(type default)
			)
			(layer "B.Fab")
		)
		(fp_line
			(start -0.120396 0.3048)
			(end -0.120396 0.2794)
			(stroke
				(width 0.1)
				(type default)
			)
			(layer "B.Fab")
		)
		(fp_line
			(start 0.12065 0.3048)
			(end 0.67945 0.3048)
			(stroke
				(width 0.1)
				(type default)
			)
			(layer "B.Fab")
		)
		(fp_line
			(start 0.67945 0.3048)
			(end 0.67945 -0.305054)
			(stroke
				(width 0.1)
				(type default)
			)
			(layer "B.Fab")
		)
		(fp_line
			(start -0.120396 0.2794)
			(end 0.12065 0.2794)
			(stroke
				(width 0.1)
				(type default)
			)
			(layer "B.Fab")
		)
		(fp_line
			(start 0.12065 0.2794)
			(end 0.12065 0.3048)
			(stroke
				(width 0.1)
				(type default)
			)
			(layer "B.Fab")
		)
		(fp_line
			(start -0.12065 -0.2794)
			(end -0.12065 -0.3048)
			(stroke
				(width 0.1)
				(type default)
			)
			(layer "B.Fab")
		)
		(fp_line
			(start 0.12065 -0.2794)
			(end -0.12065 -0.2794)
			(stroke
				(width 0.1)
				(type default)
			)
			(layer "B.Fab")
		)
		(fp_line
			(start -0.67945 -0.3048)
			(end -0.67945 0.3048)
			(stroke
				(width 0.1)
				(type default)
			)
			(layer "B.Fab")
		)
		(fp_line
			(start -0.12065 -0.3048)
			(end -0.67945 -0.3048)
			(stroke
				(width 0.1)
				(type default)
			)
			(layer "B.Fab")
		)
		(fp_line
			(start 0.12065 -0.305054)
			(end 0.12065 -0.2794)
			(stroke
				(width 0.1)
				(type default)
			)
			(layer "B.Fab")
		)
		(fp_line
			(start 0.67945 -0.305054)
			(end 0.12065 -0.305054)
			(stroke
				(width 0.1)
				(type default)
			)
			(layer "B.Fab")
		)
		(pad "1" smd circle
			(at 0.40005 0 90)
			(size 0 0)
			(layers "B.Cu" "B.Mask" "B.Paste")
			(net "CPU0_SPD_HOST_CTRL_R1_N")
		)
		(pad "2" smd circle
			(at -0.40005 0 90)
			(size 0 0)
			(layers "B.Cu" "B.Mask" "B.Paste")
			(net "CPU0_SPD_HOST_CTRL_N")
		)
	)
	(footprint ""
		(layer "B.Cu")
		(at 522.584426 -298.381674 -90)
		(property "Reference" "X11"
			(at 3.303524 3.168396 270)
			(unlocked yes)
			(layer "B.SilkS")
			(effects
				(font
					(size 0.7874 0.5842)
					(thickness 0.1524)
				)
				(justify left mirror)
			)
		)
		(property "Value" ""
			(at 0 0 90)
			(layer "B.Fab")
			(effects
				(font
					(size 1.27 1.27)
				)
				(justify mirror)
			)
		)
		(property "User Part Number" "N_A"
			(at -1.30175 1.27 180)
			(unlocked yes)
			(layer "Cmts.User")
			(hide yes)
			(effects
				(font
					(size 0.635 0.4064)
					(thickness 0.1524)
				)
				(justify mirror)
			)
		)
		(property "Device Type" "TP_TDR_4P_FTS_TH-TP_TDR_4P_DIP,EMPTY,TP15"
			(at -1.30175 1.27 180)
			(unlocked yes)
			(layer "B.Fab")
			(hide yes)
			(effects
				(font
					(size 0.635 0.4064)
					(thickness 0.1524)
				)
				(justify mirror)
			)
		)
		(duplicate_pad_numbers_are_jumpers no)
		(fp_line
			(start -2.54 3.81)
			(end -2.54 3.6703)
			(stroke
				(width 0.1524)
				(type default)
			)
			(layer "B.SilkS")
		)
		(fp_line
			(start 0 3.81)
			(end -2.54 3.81)
			(stroke
				(width 0.1524)
				(type default)
			)
			(layer "B.SilkS")
		)
		(fp_line
			(start 0 3.175)
			(end 0 3.81)
			(stroke
				(width 0.1524)
				(type default)
			)
			(layer "B.SilkS")
		)
		(fp_line
			(start -2.54 1.4097)
			(end -2.54 1.1303)
			(stroke
				(width 0.1524)
				(type default)
			)
			(layer "B.SilkS")
		)
		(fp_line
			(start 0 0.635)
			(end 0 1.905)
			(stroke
				(width 0.1524)
				(type default)
			)
			(layer "B.SilkS")
		)
		(fp_line
			(start -2.54 -1.1303)
			(end -2.54 -1.27)
			(stroke
				(width 0.1524)
				(type default)
			)
			(layer "B.SilkS")
		)
		(fp_line
			(start -2.54 -1.27)
			(end 0 -1.27)
			(stroke
				(width 0.1524)
				(type default)
			)
			(layer "B.SilkS")
		)
		(fp_line
			(start 0 -1.27)
			(end 0 -0.635)
			(stroke
				(width 0.1524)
				(type default)
			)
			(layer "B.SilkS")
		)
		(fp_poly
			(pts
				(xy 2.285746 -0.762) (xy 2.285746 0.762) (xy 0.761746 0)
			)
			(stroke
				(width 0)
				(type default)
			)
			(fill yes)
			(layer "B.SilkS")
		)
		(fp_line
			(start -2.54 3.81)
			(end -2.54 -1.27)
			(stroke
				(width 0.1)
				(type default)
			)
			(layer "B.Fab")
		)
		(fp_line
			(start 0 3.81)
			(end -2.54 3.81)
			(stroke
				(width 0.1)
				(type default)
			)
			(layer "B.Fab")
		)
		(fp_line
			(start -2.54 -1.27)
			(end 0 -1.27)
			(stroke
				(width 0.1)
				(type default)
			)
			(layer "B.Fab")
		)
		(fp_line
			(start 0 -1.27)
			(end 0 3.81)
			(stroke
				(width 0.1)
				(type default)
			)
			(layer "B.Fab")
		)
		(fp_poly
			(pts
				(xy 0.761746 0) (xy 2.285746 -0.762) (xy 2.285746 0.762)
			)
			(stroke
				(width 0)
				(type default)
			)
			(fill yes)
			(layer "B.Fab")
		)
		(pad "1" thru_hole circle
			(at 0 0 90)
			(size 1.0033 1.0033)
			(drill 0.249936)
			(layers "*.Cu" "*.Mask")
			(remove_unused_layers no)
			(net "TDR_DIFF_80_IN4_DN")
			(clearance 0.10795)
			(padstack
				(mode front_inner_back)
				(layer "Inner"
					(shape circle)
					(size 0.8001 0.8001)
					(clearance 0.1524)
				)
				(layer "B.Cu"
					(shape circle)
					(size 1.0033 1.0033)
					(thermal_gap 0.10795)
					(clearance 0.10795)
				)
			)
		)
		(pad "2" thru_hole circle
			(at -2.54 0 90)
			(size 1.9939 1.9939)
			(drill 0.249936)
			(layers "*.Cu" "*.Mask")
			(remove_unused_layers no)
			(net "T1_GND")
			(clearance 0.10795)
			(padstack
				(mode front_inner_back)
				(layer "Inner"
					(shape circle)
					(size 0.8001 0.8001)
					(clearance 0.1524)
				)
				(layer "B.Cu"
					(shape circle)
					(size 1.9939 1.9939)
					(thermal_gap 0.10795)
					(clearance 0.10795)
				)
			)
		)
		(pad "3" thru_hole circle
			(at -2.54 2.54 90)
			(size 1.9939 1.9939)
			(drill 0.249936)
			(layers "*.Cu" "*.Mask")
			(remove_unused_layers no)
			(net "T1_GND")
			(clearance 0.10795)
			(padstack
				(mode front_inner_back)
				(layer "Inner"
					(shape circle)
					(size 0.8001 0.8001)
					(clearance 0.1524)
				)
				(layer "B.Cu"
					(shape circle)
					(size 1.9939 1.9939)
					(thermal_gap 0.10795)
					(clearance 0.10795)
				)
			)
		)
		(pad "4" thru_hole circle
			(at 0 2.54 90)
			(size 1.0033 1.0033)
			(drill 0.249936)
			(layers "*.Cu" "*.Mask")
			(remove_unused_layers no)
			(net "TDR_DIFF_80_IN4_DP")
			(clearance 0.10795)
			(padstack
				(mode front_inner_back)
				(layer "Inner"
					(shape circle)
					(size 0.8001 0.8001)
					(clearance 0.1524)
				)
				(layer "B.Cu"
					(shape circle)
					(size 1.0033 1.0033)
					(thermal_gap 0.10795)
					(clearance 0.10795)
				)
			)
		)
	)
)
